(kicad_pcb
	(version 20260206)
	(generator "pcbnew")
	(generator_version "10.0")
	(general
		(thickness 1.6)
		(legacy_teardrops no)
	)
	(paper "A4")
	(title_block
		(title "03242023_DA0F0TMBIJ0_F0T_Motherboard_J_brd_V01_OCP.brd")
		(comment 1 "Grand Teton / footprints 280-286 of 6105")
	)
	(layers
		(0 "F.Cu" signal "TOP")
		(4 "In1.Cu" signal "GND")
		(6 "In2.Cu" signal "IN1")
		(8 "In3.Cu" signal "GND1")
		(10 "In4.Cu" signal "IN2")
		(12 "In5.Cu" signal "GND2")
		(14 "In6.Cu" signal "IN3")
		(16 "In7.Cu" signal "GND3")
		(18 "In8.Cu" signal "VCC")
		(20 "In9.Cu" signal "VCC1")
		(22 "In10.Cu" signal "GND4")
		(24 "In11.Cu" signal "IN4")
		(26 "In12.Cu" signal "GND5")
		(28 "In13.Cu" signal "IN5")
		(30 "In14.Cu" signal "GND6")
		(32 "In15.Cu" signal "IN6")
		(34 "In16.Cu" signal "GND7")
		(2 "B.Cu" signal "BOTTOM")
		(9 "F.Adhes" user "F.Adhesive")
		(11 "B.Adhes" user "B.Adhesive")
		(13 "F.Paste" user "Package Geometry/Pastemask Top")
		(15 "B.Paste" user "Package Geometry/Pastemask Bottom")
		(5 "F.SilkS" user "Ref Des/Silkscreen Top")
		(7 "B.SilkS" user "Ref Des/Silkscreen Bottom")
		(1 "F.Mask" user "Board Geometry/Soldermask Top")
		(3 "B.Mask" user "Board Geometry/Soldermask Bottom")
		(17 "Dwgs.User" user "User.Drawings")
		(19 "Cmts.User" user "User.Comments")
		(21 "Eco1.User" user "User.Eco1")
		(23 "Eco2.User" user "User.Eco2")
		(25 "Edge.Cuts" user "Board Geometry/Outline")
		(27 "Margin" user)
		(31 "F.CrtYd" user "Package Geometry/Place Bound Top")
		(29 "B.CrtYd" user "Package Geometry/Place Bound Bottom")
		(35 "F.Fab" user "Ref Des/Assembly Top")
		(33 "B.Fab" user "Ref Des/Assembly Bottom")
	)
	(footprint ""
		(layer "F.Cu")
		(at 164.64788 -109.565948)
		(property "Reference" "R1606"
			(at 0 0 0)
			(layer "F.SilkS")
			(hide yes)
			(effects
				(font
					(size 1.27 1.27)
				)
			)
		)
		(property "Value" ""
			(at 0 0 0)
			(layer "F.Fab")
			(effects
				(font
					(size 1.27 1.27)
				)
			)
		)
		(duplicate_pad_numbers_are_jumpers no)
		(fp_line
			(start -0.7874 -0.4064)
			(end 0.7874 -0.4064)
			(stroke
				(width 0.1524)
				(type default)
			)
			(layer "F.SilkS")
		)
		(fp_line
			(start -0.7874 0.4064)
			(end -0.7874 -0.4064)
			(stroke
				(width 0.1524)
				(type default)
			)
			(layer "F.SilkS")
		)
		(fp_line
			(start 0.7874 -0.4064)
			(end 0.7874 0.4064)
			(stroke
				(width 0.1524)
				(type default)
			)
			(layer "F.SilkS")
		)
		(fp_line
			(start 0.7874 0.4064)
			(end -0.7874 0.4064)
			(stroke
				(width 0.1524)
				(type default)
			)
			(layer "F.SilkS")
		)
		(fp_line
			(start -0.67945 -0.305054)
			(end -0.12065 -0.305054)
			(stroke
				(width 0.1)
				(type default)
			)
			(layer "F.Fab")
		)
		(fp_line
			(start -0.67945 0.3048)
			(end -0.67945 -0.305054)
			(stroke
				(width 0.1)
				(type default)
			)
			(layer "F.Fab")
		)
		(fp_line
			(start -0.12065 -0.305054)
			(end -0.12065 -0.2794)
			(stroke
				(width 0.1)
				(type default)
			)
			(layer "F.Fab")
		)
		(fp_line
			(start -0.12065 -0.2794)
			(end 0.12065 -0.2794)
			(stroke
				(width 0.1)
				(type default)
			)
			(layer "F.Fab")
		)
		(fp_line
			(start -0.12065 0.2794)
			(end -0.12065 0.3048)
			(stroke
				(width 0.1)
				(type default)
			)
			(layer "F.Fab")
		)
		(fp_line
			(start -0.12065 0.3048)
			(end -0.67945 0.3048)
			(stroke
				(width 0.1)
				(type default)
			)
			(layer "F.Fab")
		)
		(fp_line
			(start 0.120396 0.2794)
			(end -0.12065 0.2794)
			(stroke
				(width 0.1)
				(type default)
			)
			(layer "F.Fab")
		)
		(fp_line
			(start 0.120396 0.3048)
			(end 0.120396 0.2794)
			(stroke
				(width 0.1)
				(type default)
			)
			(layer "F.Fab")
		)
		(fp_line
			(start 0.12065 -0.3048)
			(end 0.67945 -0.3048)
			(stroke
				(width 0.1)
				(type default)
			)
			(layer "F.Fab")
		)
		(fp_line
			(start 0.12065 -0.2794)
			(end 0.12065 -0.3048)
			(stroke
				(width 0.1)
				(type default)
			)
			(layer "F.Fab")
		)
		(fp_line
			(start 0.67945 -0.3048)
			(end 0.67945 0.3048)
			(stroke
				(width 0.1)
				(type default)
			)
			(layer "F.Fab")
		)
		(fp_line
			(start 0.67945 0.3048)
			(end 0.120396 0.3048)
			(stroke
				(width 0.1)
				(type default)
			)
			(layer "F.Fab")
		)
		(pad "1" smd circle
			(at -0.40005 0)
			(size 0 0)
			(layers "F.Cu" "F.Mask" "F.Paste")
			(net "FM_OCP_SFF_PWR_GOOD")
		)
		(pad "2" smd circle
			(at 0.40005 0)
			(size 0 0)
			(layers "F.Cu" "F.Mask" "F.Paste")
			(net "FM_OCP_SFF_PWR_GOOD_R")
		)
	)
	(footprint ""
		(layer "F.Cu")
		(at 431.989992 -386.171948 180)
		(property "Reference" "R2841"
			(at 0 0 180)
			(layer "F.SilkS")
			(hide yes)
			(effects
				(font
					(size 1.27 1.27)
				)
			)
		)
		(property "Value" ""
			(at 0 0 180)
			(layer "F.Fab")
			(effects
				(font
					(size 1.27 1.27)
				)
			)
		)
		(duplicate_pad_numbers_are_jumpers no)
		(fp_line
			(start 0.7874 0.4064)
			(end -0.7874 0.4064)
			(stroke
				(width 0.1524)
				(type default)
			)
			(layer "F.SilkS")
		)
		(fp_line
			(start 0.7874 -0.4064)
			(end 0.7874 0.4064)
			(stroke
				(width 0.1524)
				(type default)
			)
			(layer "F.SilkS")
		)
		(fp_line
			(start -0.7874 0.4064)
			(end -0.7874 -0.4064)
			(stroke
				(width 0.1524)
				(type default)
			)
			(layer "F.SilkS")
		)
		(fp_line
			(start -0.7874 -0.4064)
			(end 0.7874 -0.4064)
			(stroke
				(width 0.1524)
				(type default)
			)
			(layer "F.SilkS")
		)
		(fp_line
			(start 0.67945 0.3048)
			(end 0.120396 0.3048)
			(stroke
				(width 0.1)
				(type default)
			)
			(layer "F.Fab")
		)
		(fp_line
			(start 0.67945 -0.3048)
			(end 0.67945 0.3048)
			(stroke
				(width 0.1)
				(type default)
			)
			(layer "F.Fab")
		)
		(fp_line
			(start 0.12065 -0.2794)
			(end 0.12065 -0.3048)
			(stroke
				(width 0.1)
				(type default)
			)
			(layer "F.Fab")
		)
		(fp_line
			(start 0.12065 -0.3048)
			(end 0.67945 -0.3048)
			(stroke
				(width 0.1)
				(type default)
			)
			(layer "F.Fab")
		)
		(fp_line
			(start 0.120396 0.3048)
			(end 0.120396 0.2794)
			(stroke
				(width 0.1)
				(type default)
			)
			(layer "F.Fab")
		)
		(fp_line
			(start 0.120396 0.2794)
			(end -0.12065 0.2794)
			(stroke
				(width 0.1)
				(type default)
			)
			(layer "F.Fab")
		)
		(fp_line
			(start -0.12065 0.3048)
			(end -0.67945 0.3048)
			(stroke
				(width 0.1)
				(type default)
			)
			(layer "F.Fab")
		)
		(fp_line
			(start -0.12065 0.2794)
			(end -0.12065 0.3048)
			(stroke
				(width 0.1)
				(type default)
			)
			(layer "F.Fab")
		)
		(fp_line
			(start -0.12065 -0.2794)
			(end 0.12065 -0.2794)
			(stroke
				(width 0.1)
				(type default)
			)
			(layer "F.Fab")
		)
		(fp_line
			(start -0.12065 -0.305054)
			(end -0.12065 -0.2794)
			(stroke
				(width 0.1)
				(type default)
			)
			(layer "F.Fab")
		)
		(fp_line
			(start -0.67945 0.3048)
			(end -0.67945 -0.305054)
			(stroke
				(width 0.1)
				(type default)
			)
			(layer "F.Fab")
		)
		(fp_line
			(start -0.67945 -0.305054)
			(end -0.12065 -0.305054)
			(stroke
				(width 0.1)
				(type default)
			)
			(layer "F.Fab")
		)
		(pad "1" smd circle
			(at -0.40005 0 180)
			(size 0 0)
			(layers "F.Cu" "F.Mask" "F.Paste")
			(net "P3V3_AUX")
		)
		(pad "2" smd circle
			(at 0.40005 0 180)
			(size 0 0)
			(layers "F.Cu" "F.Mask" "F.Paste")
			(net "FM_SWB_PWRGD_N")
		)
	)
	(footprint ""
		(layer "F.Cu")
		(at 36.14928 -433.923948 180)
		(property "Reference" "R3226"
			(at 0 0 180)
			(layer "F.SilkS")
			(hide yes)
			(effects
				(font
					(size 1.27 1.27)
				)
			)
		)
		(property "Value" ""
			(at 0 0 180)
			(layer "F.Fab")
			(effects
				(font
					(size 1.27 1.27)
				)
			)
		)
		(duplicate_pad_numbers_are_jumpers no)
		(fp_line
			(start 0.7874 0.4064)
			(end -0.7874 0.4064)
			(stroke
				(width 0.1524)
				(type default)
			)
			(layer "F.SilkS")
		)
		(fp_line
			(start 0.7874 -0.4064)
			(end 0.7874 0.4064)
			(stroke
				(width 0.1524)
				(type default)
			)
			(layer "F.SilkS")
		)
		(fp_line
			(start -0.7874 0.4064)
			(end -0.7874 -0.4064)
			(stroke
				(width 0.1524)
				(type default)
			)
			(layer "F.SilkS")
		)
		(fp_line
			(start -0.7874 -0.4064)
			(end 0.7874 -0.4064)
			(stroke
				(width 0.1524)
				(type default)
			)
			(layer "F.SilkS")
		)
		(fp_line
			(start 0.67945 0.3048)
			(end 0.120396 0.3048)
			(stroke
				(width 0.1)
				(type default)
			)
			(layer "F.Fab")
		)
		(fp_line
			(start 0.67945 -0.3048)
			(end 0.67945 0.3048)
			(stroke
				(width 0.1)
				(type default)
			)
			(layer "F.Fab")
		)
		(fp_line
			(start 0.12065 -0.2794)
			(end 0.12065 -0.3048)
			(stroke
				(width 0.1)
				(type default)
			)
			(layer "F.Fab")
		)
		(fp_line
			(start 0.12065 -0.3048)
			(end 0.67945 -0.3048)
			(stroke
				(width 0.1)
				(type default)
			)
			(layer "F.Fab")
		)
		(fp_line
			(start 0.120396 0.3048)
			(end 0.120396 0.2794)
			(stroke
				(width 0.1)
				(type default)
			)
			(layer "F.Fab")
		)
		(fp_line
			(start 0.120396 0.2794)
			(end -0.12065 0.2794)
			(stroke
				(width 0.1)
				(type default)
			)
			(layer "F.Fab")
		)
		(fp_line
			(start -0.12065 0.3048)
			(end -0.67945 0.3048)
			(stroke
				(width 0.1)
				(type default)
			)
			(layer "F.Fab")
		)
		(fp_line
			(start -0.12065 0.2794)
			(end -0.12065 0.3048)
			(stroke
				(width 0.1)
				(type default)
			)
			(layer "F.Fab")
		)
		(fp_line
			(start -0.12065 -0.2794)
			(end 0.12065 -0.2794)
			(stroke
				(width 0.1)
				(type default)
			)
			(layer "F.Fab")
		)
		(fp_line
			(start -0.12065 -0.305054)
			(end -0.12065 -0.2794)
			(stroke
				(width 0.1)
				(type default)
			)
			(layer "F.Fab")
		)
		(fp_line
			(start -0.67945 0.3048)
			(end -0.67945 -0.305054)
			(stroke
				(width 0.1)
				(type default)
			)
			(layer "F.Fab")
		)
		(fp_line
			(start -0.67945 -0.305054)
			(end -0.12065 -0.305054)
			(stroke
				(width 0.1)
				(type default)
			)
			(layer "F.Fab")
		)
		(pad "1" smd circle
			(at -0.40005 0 180)
			(size 0 0)
			(layers "F.Cu" "F.Mask" "F.Paste")
			(net "SMB_1_BMC_GPU_SCL")
		)
		(pad "2" smd circle
			(at 0.40005 0 180)
			(size 0 0)
			(layers "F.Cu" "F.Mask" "F.Paste")
			(net "P3V3_AUX")
		)
	)
	(footprint ""
		(layer "F.Cu")
		(at 455.123804 -71.245984 -90)
		(property "Reference" "PC567"
			(at 0 0 270)
			(layer "F.SilkS")
			(hide yes)
			(effects
				(font
					(size 1.27 1.27)
				)
			)
		)
		(property "Value" ""
			(at 0 0 270)
			(layer "F.Fab")
			(effects
				(font
					(size 1.27 1.27)
				)
			)
		)
		(duplicate_pad_numbers_are_jumpers no)
		(fp_line
			(start -1.524 0.762)
			(end -1.524 -0.762)
			(stroke
				(width 0.1524)
				(type default)
			)
			(layer "F.SilkS")
		)
		(fp_line
			(start 1.524 0.762)
			(end -1.524 0.762)
			(stroke
				(width 0.1524)
				(type default)
			)
			(layer "F.SilkS")
		)
		(fp_line
			(start -1.524 -0.762)
			(end 1.524 -0.762)
			(stroke
				(width 0.1524)
				(type default)
			)
			(layer "F.SilkS")
		)
		(fp_line
			(start 1.524 -0.762)
			(end 1.524 0.762)
			(stroke
				(width 0.1524)
				(type default)
			)
			(layer "F.SilkS")
		)
		(fp_line
			(start -1.1049 0.724916)
			(end 1.1049 0.724916)
			(stroke
				(width 0.1)
				(type default)
			)
			(layer "F.Fab")
		)
		(fp_line
			(start 1.1049 0.724916)
			(end 1.1049 -0.724916)
			(stroke
				(width 0.1)
				(type default)
			)
			(layer "F.Fab")
		)
		(fp_line
			(start -1.1049 -0.724916)
			(end -1.1049 0.724916)
			(stroke
				(width 0.1)
				(type default)
			)
			(layer "F.Fab")
		)
		(fp_line
			(start 1.1049 -0.724916)
			(end -1.1049 -0.724916)
			(stroke
				(width 0.1)
				(type default)
			)
			(layer "F.Fab")
		)
		(pad "1" smd rect
			(at -0.889 0 90)
			(size 1.016 1.27)
			(layers "F.Cu" "F.Mask" "F.Paste")
			(net "SW_P3V3_AUX_FLT")
		)
		(pad "2" smd rect
			(at 0.889 0 90)
			(size 1.016 1.27)
			(layers "F.Cu" "F.Mask" "F.Paste")
			(net "GND")
		)
	)
	(footprint ""
		(layer "F.Cu")
		(at 36.930584 -106.523282)
		(property "Reference" "C2050"
			(at 0 0 0)
			(layer "F.SilkS")
			(hide yes)
			(effects
				(font
					(size 1.27 1.27)
				)
			)
		)
		(property "Value" ""
			(at 0 0 0)
			(layer "F.Fab")
			(effects
				(font
					(size 1.27 1.27)
				)
			)
		)
		(duplicate_pad_numbers_are_jumpers no)
		(fp_line
			(start -0.7874 -0.4064)
			(end 0.7874 -0.4064)
			(stroke
				(width 0.1524)
				(type default)
			)
			(layer "F.SilkS")
		)
		(fp_line
			(start -0.7874 0.4064)
			(end -0.7874 -0.4064)
			(stroke
				(width 0.1524)
				(type default)
			)
			(layer "F.SilkS")
		)
		(fp_line
			(start 0.7874 -0.4064)
			(end 0.7874 0.4064)
			(stroke
				(width 0.1524)
				(type default)
			)
			(layer "F.SilkS")
		)
		(fp_line
			(start 0.7874 0.4064)
			(end -0.7874 0.4064)
			(stroke
				(width 0.1524)
				(type default)
			)
			(layer "F.SilkS")
		)
		(fp_line
			(start -0.67945 -0.305054)
			(end -0.12065 -0.305054)
			(stroke
				(width 0.1)
				(type default)
			)
			(layer "F.Fab")
		)
		(fp_line
			(start -0.67945 0.3048)
			(end -0.67945 -0.305054)
			(stroke
				(width 0.1)
				(type default)
			)
			(layer "F.Fab")
		)
		(fp_line
			(start -0.12065 -0.305054)
			(end -0.12065 -0.2794)
			(stroke
				(width 0.1)
				(type default)
			)
			(layer "F.Fab")
		)
		(fp_line
			(start -0.12065 -0.2794)
			(end 0.12065 -0.2794)
			(stroke
				(width 0.1)
				(type default)
			)
			(layer "F.Fab")
		)
		(fp_line
			(start -0.12065 0.2794)
			(end -0.12065 0.3048)
			(stroke
				(width 0.1)
				(type default)
			)
			(layer "F.Fab")
		)
		(fp_line
			(start -0.12065 0.3048)
			(end -0.67945 0.3048)
			(stroke
				(width 0.1)
				(type default)
			)
			(layer "F.Fab")
		)
		(fp_line
			(start 0.120396 0.2794)
			(end -0.12065 0.2794)
			(stroke
				(width 0.1)
				(type default)
			)
			(layer "F.Fab")
		)
		(fp_line
			(start 0.120396 0.3048)
			(end 0.120396 0.2794)
			(stroke
				(width 0.1)
				(type default)
			)
			(layer "F.Fab")
		)
		(fp_line
			(start 0.12065 -0.3048)
			(end 0.67945 -0.3048)
			(stroke
				(width 0.1)
				(type default)
			)
			(layer "F.Fab")
		)
		(fp_line
			(start 0.12065 -0.2794)
			(end 0.12065 -0.3048)
			(stroke
				(width 0.1)
				(type default)
			)
			(layer "F.Fab")
		)
		(fp_line
			(start 0.67945 -0.3048)
			(end 0.67945 0.3048)
			(stroke
				(width 0.1)
				(type default)
			)
			(layer "F.Fab")
		)
		(fp_line
			(start 0.67945 0.3048)
			(end 0.120396 0.3048)
			(stroke
				(width 0.1)
				(type default)
			)
			(layer "F.Fab")
		)
		(pad "1" smd circle
			(at -0.40005 0)
			(size 0 0)
			(layers "F.Cu" "F.Mask" "F.Paste")
			(net "P3V3_PDB_AUX_ADC_TIC")
		)
		(pad "2" smd circle
			(at 0.40005 0)
			(size 0 0)
			(layers "F.Cu" "F.Mask" "F.Paste")
			(net "GND")
		)
	)
	(footprint ""
		(layer "F.Cu")
		(at 299.6946 -346.700348)
		(property "Reference" "PC619"
			(at 0 0 0)
			(layer "F.SilkS")
			(hide yes)
			(effects
				(font
					(size 1.27 1.27)
				)
			)
		)
		(property "Value" ""
			(at 0 0 0)
			(layer "F.Fab")
			(effects
				(font
					(size 1.27 1.27)
				)
			)
		)
		(duplicate_pad_numbers_are_jumpers no)
		(fp_line
			(start 2.750058 0.999998)
			(end -2.750058 0.999998)
			(stroke
				(width 0.1524)
				(type default)
			)
			(layer "F.SilkS")
		)
		(fp_circle
			(center 0 0.999998)
			(end 2.750058 0.999998)
			(stroke
				(width 0.1524)
				(type default)
			)
			(fill no)
			(layer "F.SilkS")
		)
		(fp_poly
			(pts
				(arc
					(start 2.750058 0.999998)
					(mid 0 3.750056)
					(end -2.750058 0.999998)
				)
			)
			(stroke
				(width 0)
				(type default)
			)
			(fill yes)
			(layer "F.SilkS")
		)
		(fp_circle
			(center 0 0.999998)
			(end 2.750058 0.999998)
			(stroke
				(width 0.1)
				(type default)
			)
			(fill no)
			(layer "F.Fab")
		)
		(pad "1" thru_hole rect
			(at 0 0)
			(size 1.5748 1.5748)
			(drill 1.0668)
			(layers "*.Cu" "*.Mask")
			(remove_unused_layers no)
			(net "PVCCFA_EHV_FIVRA_CPU0")
			(clearance 0)
			(padstack
				(mode front_inner_back)
				(layer "Inner"
					(shape circle)
					(size 1.5748 1.5748)
					(clearance 0)
				)
				(layer "B.Cu"
					(shape rect)
					(size 1.5748 1.5748)
					(clearance 0)
				)
			)
		)
		(pad "2" thru_hole circle
			(at 0 1.999996)
			(size 1.5748 1.5748)
			(drill 1.0668)
			(layers "*.Cu" "*.Mask")
			(remove_unused_layers no)
			(net "GND")
			(clearance 0)
		)
	)
	(footprint ""
		(layer "F.Cu")
		(at 70.358 -113.756948 180)
		(property "Reference" "R4269"
			(at 0 0 180)
			(layer "F.SilkS")
			(hide yes)
			(effects
				(font
					(size 1.27 1.27)
				)
			)
		)
		(property "Value" ""
			(at 0 0 180)
			(layer "F.Fab")
			(effects
				(font
					(size 1.27 1.27)
				)
			)
		)
		(duplicate_pad_numbers_are_jumpers no)
		(fp_line
			(start 0.7874 0.4064)
			(end -0.7874 0.4064)
			(stroke
				(width 0.1524)
				(type default)
			)
			(layer "F.SilkS")
		)
		(fp_line
			(start 0.7874 -0.4064)
			(end 0.7874 0.4064)
			(stroke
				(width 0.1524)
				(type default)
			)
			(layer "F.SilkS")
		)
		(fp_line
			(start -0.7874 0.4064)
			(end -0.7874 -0.4064)
			(stroke
				(width 0.1524)
				(type default)
			)
			(layer "F.SilkS")
		)
		(fp_line
			(start -0.7874 -0.4064)
			(end 0.7874 -0.4064)
			(stroke
				(width 0.1524)
				(type default)
			)
			(layer "F.SilkS")
		)
		(fp_line
			(start 0.67945 0.3048)
			(end 0.120396 0.3048)
			(stroke
				(width 0.1)
				(type default)
			)
			(layer "F.Fab")
		)
		(fp_line
			(start 0.67945 -0.3048)
			(end 0.67945 0.3048)
			(stroke
				(width 0.1)
				(type default)
			)
			(layer "F.Fab")
		)
		(fp_line
			(start 0.12065 -0.2794)
			(end 0.12065 -0.3048)
			(stroke
				(width 0.1)
				(type default)
			)
			(layer "F.Fab")
		)
		(fp_line
			(start 0.12065 -0.3048)
			(end 0.67945 -0.3048)
			(stroke
				(width 0.1)
				(type default)
			)
			(layer "F.Fab")
		)
		(fp_line
			(start 0.120396 0.3048)
			(end 0.120396 0.2794)
			(stroke
				(width 0.1)
				(type default)
			)
			(layer "F.Fab")
		)
		(fp_line
			(start 0.120396 0.2794)
			(end -0.12065 0.2794)
			(stroke
				(width 0.1)
				(type default)
			)
			(layer "F.Fab")
		)
		(fp_line
			(start -0.12065 0.3048)
			(end -0.67945 0.3048)
			(stroke
				(width 0.1)
				(type default)
			)
			(layer "F.Fab")
		)
		(fp_line
			(start -0.12065 0.2794)
			(end -0.12065 0.3048)
			(stroke
				(width 0.1)
				(type default)
			)
			(layer "F.Fab")
		)
		(fp_line
			(start -0.12065 -0.2794)
			(end 0.12065 -0.2794)
			(stroke
				(width 0.1)
				(type default)
			)
			(layer "F.Fab")
		)
		(fp_line
			(start -0.12065 -0.305054)
			(end -0.12065 -0.2794)
			(stroke
				(width 0.1)
				(type default)
			)
			(layer "F.Fab")
		)
		(fp_line
			(start -0.67945 0.3048)
			(end -0.67945 -0.305054)
			(stroke
				(width 0.1)
				(type default)
			)
			(layer "F.Fab")
		)
		(fp_line
			(start -0.67945 -0.305054)
			(end -0.12065 -0.305054)
			(stroke
				(width 0.1)
				(type default)
			)
			(layer "F.Fab")
		)
		(pad "1" smd circle
			(at -0.40005 0 180)
			(size 0 0)
			(layers "F.Cu" "F.Mask" "F.Paste")
			(net "P3V3_AUX")
		)
		(pad "2" smd circle
			(at 0.40005 0 180)
			(size 0 0)
			(layers "F.Cu" "F.Mask" "F.Paste")
			(net "SMB_VR_SENSOR_3V3AUX_SCL")
		)
	)
)
